# S9S_MB_2U (Grand Teton) — schematic netlist excerpt (pin names and nets, part order shuffled) for the footprints in the layout excerpt that follows; sources: Cadence DE-HDL packaged netlist, KiCad conversion of 03242023_DA0F0TMBIJ0_F0T_Motherboard_J_brd_V01_OCP.brd

R292  Q_RES  240 1% EMPTY  pkg 0402LF  page 119 : A = PVNN_TERM_CPU0 ; B = PD_CPU0_TXT_PLTEN
R162  Q_RES  0 5% CHIP  pkg 0402LF  page 124 : A = PWRGD_DRAMPWRGD_CPU0_CD_R_LVC1 ; B = PWRGD_DRAMPWRGD_CPU0_CD_LVC1_R2

(kicad_pcb
	(version 20260206)
	(generator "pcbnew")
	(generator_version "10.0")
	(general
		(thickness 1.6)
		(legacy_teardrops no)
	)
	(paper "A4")
	(title_block
		(title "03242023_DA0F0TMBIJ0_F0T_Motherboard_J_brd_V01_OCP.brd")
		(comment 1 "Grand Teton / footprints 4218-4219 of 6105")
	)
	(layers
		(0 "F.Cu" signal "TOP")
		(4 "In1.Cu" signal "GND")
		(6 "In2.Cu" signal "IN1")
		(8 "In3.Cu" signal "GND1")
		(10 "In4.Cu" signal "IN2")
		(12 "In5.Cu" signal "GND2")
		(14 "In6.Cu" signal "IN3")
		(16 "In7.Cu" signal "GND3")
		(18 "In8.Cu" signal "VCC")
		(20 "In9.Cu" signal "VCC1")
		(22 "In10.Cu" signal "GND4")
		(24 "In11.Cu" signal "IN4")
		(26 "In12.Cu" signal "GND5")
		(28 "In13.Cu" signal "IN5")
		(30 "In14.Cu" signal "GND6")
		(32 "In15.Cu" signal "IN6")
		(34 "In16.Cu" signal "GND7")
		(2 "B.Cu" signal "BOTTOM")
		(9 "F.Adhes" user "F.Adhesive")
		(11 "B.Adhes" user "B.Adhesive")
		(13 "F.Paste" user "Package Geometry/Pastemask Top")
		(15 "B.Paste" user "Package Geometry/Pastemask Bottom")
		(5 "F.SilkS" user "Ref Des/Silkscreen Top")
		(7 "B.SilkS" user "Ref Des/Silkscreen Bottom")
		(1 "F.Mask" user "Board Geometry/Soldermask Top")
		(3 "B.Mask" user "Board Geometry/Soldermask Bottom")
		(17 "Dwgs.User" user "User.Drawings")
		(19 "Cmts.User" user "User.Comments")
		(21 "Eco1.User" user "User.Eco1")
		(23 "Eco2.User" user "User.Eco2")
		(25 "Edge.Cuts" user "Board Geometry/Outline")
		(27 "Margin" user)
		(31 "F.CrtYd" user "Package Geometry/Place Bound Top")
		(29 "B.CrtYd" user "Package Geometry/Place Bound Bottom")
		(35 "F.Fab" user "Ref Des/Assembly Top")
		(33 "B.Fab" user "Ref Des/Assembly Bottom")
	)
	(footprint ""
		(layer "B.Cu")
		(at 175.830738 -97.32137 -90)
		(property "Reference" "R162"
			(at 0 0 90)
			(layer "B.SilkS")
			(hide yes)
			(effects
				(font
					(size 1.27 1.27)
				)
				(justify mirror)
			)
		)
		(property "Value" ""
			(at 0 0 90)
			(layer "B.Fab")
			(effects
				(font
					(size 1.27 1.27)
				)
				(justify mirror)
			)
		)
		(duplicate_pad_numbers_are_jumpers no)
		(fp_line
			(start -0.7874 0.4064)
			(end 0.7874 0.4064)
			(stroke
				(width 0.1524)
				(type default)
			)
			(layer "B.SilkS")
		)
		(fp_line
			(start 0.7874 0.4064)
			(end 0.7874 -0.4064)
			(stroke
				(width 0.1524)
				(type default)
			)
			(layer "B.SilkS")
		)
		(fp_line
			(start -0.7874 -0.4064)
			(end -0.7874 0.4064)
			(stroke
				(width 0.1524)
				(type default)
			)
			(layer "B.SilkS")
		)
		(fp_line
			(start 0.7874 -0.4064)
			(end -0.7874 -0.4064)
			(stroke
				(width 0.1524)
				(type default)
			)
			(layer "B.SilkS")
		)
		(fp_line
			(start -0.67945 0.3048)
			(end -0.120396 0.3048)
			(stroke
				(width 0.1)
				(type default)
			)
			(layer "B.Fab")
		)
		(fp_line
			(start -0.120396 0.3048)
			(end -0.120396 0.2794)
			(stroke
				(width 0.1)
				(type default)
			)
			(layer "B.Fab")
		)
		(fp_line
			(start 0.12065 0.3048)
			(end 0.67945 0.3048)
			(stroke
				(width 0.1)
				(type default)
			)
			(layer "B.Fab")
		)
		(fp_line
			(start 0.67945 0.3048)
			(end 0.67945 -0.305054)
			(stroke
				(width 0.1)
				(type default)
			)
			(layer "B.Fab")
		)
		(fp_line
			(start -0.120396 0.2794)
			(end 0.12065 0.2794)
			(stroke
				(width 0.1)
				(type default)
			)
			(layer "B.Fab")
		)
		(fp_line
			(start 0.12065 0.2794)
			(end 0.12065 0.3048)
			(stroke
				(width 0.1)
				(type default)
			)
			(layer "B.Fab")
		)
		(fp_line
			(start -0.12065 -0.2794)
			(end -0.12065 -0.3048)
			(stroke
				(width 0.1)
				(type default)
			)
			(layer "B.Fab")
		)
		(fp_line
			(start 0.12065 -0.2794)
			(end -0.12065 -0.2794)
			(stroke
				(width 0.1)
				(type default)
			)
			(layer "B.Fab")
		)
		(fp_line
			(start -0.67945 -0.3048)
			(end -0.67945 0.3048)
			(stroke
				(width 0.1)
				(type default)
			)
			(layer "B.Fab")
		)
		(fp_line
			(start -0.12065 -0.3048)
			(end -0.67945 -0.3048)
			(stroke
				(width 0.1)
				(type default)
			)
			(layer "B.Fab")
		)
		(fp_line
			(start 0.12065 -0.305054)
			(end 0.12065 -0.2794)
			(stroke
				(width 0.1)
				(type default)
			)
			(layer "B.Fab")
		)
		(fp_line
			(start 0.67945 -0.305054)
			(end 0.12065 -0.305054)
			(stroke
				(width 0.1)
				(type default)
			)
			(layer "B.Fab")
		)
		(pad "1" smd circle
			(at 0.40005 0 90)
			(size 0 0)
			(layers "B.Cu" "B.Mask" "B.Paste")
			(net "PWRGD_DRAMPWRGD_CPU0_CD_R_LVC1")
		)
		(pad "2" smd circle
			(at -0.40005 0 90)
			(size 0 0)
			(layers "B.Cu" "B.Mask" "B.Paste")
			(net "PWRGD_DRAMPWRGD_CPU0_CD_LVC1_R2")
		)
	)
	(footprint ""
		(layer "B.Cu")
		(at 382.782064 -186.935364 90)
		(property "Reference" "R292"
			(at 0 0 90)
			(layer "B.SilkS")
			(hide yes)
			(effects
				(font
					(size 1.27 1.27)
				)
				(justify mirror)
			)
		)
		(property "Value" ""
			(at 0 0 90)
			(layer "B.Fab")
			(effects
				(font
					(size 1.27 1.27)
				)
				(justify mirror)
			)
		)
		(duplicate_pad_numbers_are_jumpers no)
		(fp_line
			(start 0.7874 -0.4064)
			(end -0.7874 -0.4064)
			(stroke
				(width 0.1524)
				(type default)
			)
			(layer "B.SilkS")
		)
		(fp_line
			(start -0.7874 -0.4064)
			(end -0.7874 0.4064)
			(stroke
				(width 0.1524)
				(type default)
			)
			(layer "B.SilkS")
		)
		(fp_line
			(start 0.7874 0.4064)
			(end 0.7874 -0.4064)
			(stroke
				(width 0.1524)
				(type default)
			)
			(layer "B.SilkS")
		)
		(fp_line
			(start -0.7874 0.4064)
			(end 0.7874 0.4064)
			(stroke
				(width 0.1524)
				(type default)
			)
			(layer "B.SilkS")
		)
		(fp_line
			(start 0.67945 -0.305054)
			(end 0.12065 -0.305054)
			(stroke
				(width 0.1)
				(type default)
			)
			(layer "B.Fab")
		)
		(fp_line
			(start 0.12065 -0.305054)
			(end 0.12065 -0.2794)
			(stroke
				(width 0.1)
				(type default)
			)
			(layer "B.Fab")
		)
		(fp_line
			(start -0.12065 -0.3048)
			(end -0.67945 -0.3048)
			(stroke
				(width 0.1)
				(type default)
			)
			(layer "B.Fab")
		)
		(fp_line
			(start -0.67945 -0.3048)
			(end -0.67945 0.3048)
			(stroke
				(width 0.1)
				(type default)
			)
			(layer "B.Fab")
		)
		(fp_line
			(start 0.12065 -0.2794)
			(end -0.12065 -0.2794)
			(stroke
				(width 0.1)
				(type default)
			)
			(layer "B.Fab")
		)
		(fp_line
			(start -0.12065 -0.2794)
			(end -0.12065 -0.3048)
			(stroke
				(width 0.1)
				(type default)
			)
			(layer "B.Fab")
		)
		(fp_line
			(start 0.12065 0.2794)
			(end 0.12065 0.3048)
			(stroke
				(width 0.1)
				(type default)
			)
			(layer "B.Fab")
		)
		(fp_line
			(start -0.120396 0.2794)
			(end 0.12065 0.2794)
			(stroke
				(width 0.1)
				(type default)
			)
			(layer "B.Fab")
		)
		(fp_line
			(start 0.67945 0.3048)
			(end 0.67945 -0.305054)
			(stroke
				(width 0.1)
				(type default)
			)
			(layer "B.Fab")
		)
		(fp_line
			(start 0.12065 0.3048)
			(end 0.67945 0.3048)
			(stroke
				(width 0.1)
				(type default)
			)
			(layer "B.Fab")
		)
		(fp_line
			(start -0.120396 0.3048)
			(end -0.120396 0.2794)
			(stroke
				(width 0.1)
				(type default)
			)
			(layer "B.Fab")
		)
		(fp_line
			(start -0.67945 0.3048)
			(end -0.120396 0.3048)
			(stroke
				(width 0.1)
				(type default)
			)
			(layer "B.Fab")
		)
		(pad "1" smd circle
			(at 0.40005 0 270)
			(size 0 0)
			(layers "B.Cu" "B.Mask" "B.Paste")
			(net "PVNN_TERM_CPU0")
		)
		(pad "2" smd circle
			(at -0.40005 0 270)
			(size 0 0)
			(layers "B.Cu" "B.Mask" "B.Paste")
			(net "PD_CPU0_TXT_PLTEN")
		)
	)
)
